# T6G (Grand Teton) — schematic netlist excerpt (pin names and nets, part order shuffled) for the footprints in the layout excerpt that follows; sources: Cadence DE-HDL packaged netlist, KiCad conversion of 04192023_DAF0TMB3IC0_F0TG_MB_C_brd_V02_OCP.brd

R631  Q_RES  51.1 1% EMPTY  pkg 0201LF  page 298 : A = CLK_100M_RETIMER_CPU0_P2_DN ; B = GND
R1283  Q_RES  10 1% CHIP  pkg 0402LF  page 357 : A = P12V_E1S_0 ; B = VSENSE_P12V_INA230_8_INP
PC1320  Q_CAP  2.2UF 16V 20% X7R  pkg C0603  page 141 : A = P12V_OCP_AVIN_PD_2 ; B = GND

(kicad_pcb
	(version 20260206)
	(generator "pcbnew")
	(generator_version "10.0")
	(general
		(thickness 1.6)
		(legacy_teardrops no)
	)
	(paper "A4")
	(title_block
		(title "04192023_DAF0TMB3IC0_F0TG_MB_C_brd_V02_OCP.brd")
		(comment 1 "Grand Teton / footprints 4707-4709 of 8354")
	)
	(layers
		(0 "F.Cu" signal "TOP")
		(4 "In1.Cu" signal "GND")
		(6 "In2.Cu" signal "IN1")
		(8 "In3.Cu" signal "GND1")
		(10 "In4.Cu" signal "IN2")
		(12 "In5.Cu" signal "GND2")
		(14 "In6.Cu" signal "IN3")
		(16 "In7.Cu" signal "GND3")
		(18 "In8.Cu" signal "VCC")
		(20 "In9.Cu" signal "VCC1")
		(22 "In10.Cu" signal "GND4")
		(24 "In11.Cu" signal "IN4")
		(26 "In12.Cu" signal "GND5")
		(28 "In13.Cu" signal "IN5")
		(30 "In14.Cu" signal "GND6")
		(32 "In15.Cu" signal "IN6")
		(34 "In16.Cu" signal "GND7")
		(2 "B.Cu" signal "BOTTOM")
		(9 "F.Adhes" user "F.Adhesive")
		(11 "B.Adhes" user "B.Adhesive")
		(13 "F.Paste" user "Package Geometry/Pastemask Top")
		(15 "B.Paste" user "Package Geometry/Pastemask Bottom")
		(5 "F.SilkS" user "Ref Des/Silkscreen Top")
		(7 "B.SilkS" user "Ref Des/Silkscreen Bottom")
		(1 "F.Mask" user "Board Geometry/Soldermask Top")
		(3 "B.Mask" user "Board Geometry/Soldermask Bottom")
		(17 "Dwgs.User" user "User.Drawings")
		(19 "Cmts.User" user "User.Comments")
		(21 "Eco1.User" user "User.Eco1")
		(23 "Eco2.User" user "User.Eco2")
		(25 "Edge.Cuts" user "Board Geometry/Outline")
		(27 "Margin" user)
		(31 "F.CrtYd" user "Package Geometry/Place Bound Top")
		(29 "B.CrtYd" user "Package Geometry/Place Bound Bottom")
		(35 "F.Fab" user "Ref Des/Assembly Top")
		(33 "B.Fab" user "Ref Des/Assembly Bottom")
	)
	(footprint ""
		(layer "F.Cu")
		(at 245.52275 -50.335434 180)
		(property "Reference" "R1283"
			(at 0 0 180)
			(layer "F.SilkS")
			(hide yes)
			(effects
				(font
					(size 1.27 1.27)
				)
			)
		)
		(property "Value" ""
			(at 0 0 180)
			(layer "F.Fab")
			(effects
				(font
					(size 1.27 1.27)
				)
			)
		)
		(duplicate_pad_numbers_are_jumpers no)
		(fp_line
			(start 0.7874 0.4064)
			(end -0.7874 0.4064)
			(stroke
				(width 0.1524)
				(type default)
			)
			(layer "F.SilkS")
		)
		(fp_line
			(start 0.7874 -0.4064)
			(end 0.7874 0.4064)
			(stroke
				(width 0.1524)
				(type default)
			)
			(layer "F.SilkS")
		)
		(fp_line
			(start -0.7874 0.4064)
			(end -0.7874 -0.4064)
			(stroke
				(width 0.1524)
				(type default)
			)
			(layer "F.SilkS")
		)
		(fp_line
			(start -0.7874 -0.4064)
			(end 0.7874 -0.4064)
			(stroke
				(width 0.1524)
				(type default)
			)
			(layer "F.SilkS")
		)
		(fp_line
			(start 0.67945 0.3048)
			(end 0.120396 0.3048)
			(stroke
				(width 0.1)
				(type default)
			)
			(layer "F.Fab")
		)
		(fp_line
			(start 0.67945 -0.3048)
			(end 0.67945 0.3048)
			(stroke
				(width 0.1)
				(type default)
			)
			(layer "F.Fab")
		)
		(fp_line
			(start 0.12065 -0.2794)
			(end 0.12065 -0.3048)
			(stroke
				(width 0.1)
				(type default)
			)
			(layer "F.Fab")
		)
		(fp_line
			(start 0.12065 -0.3048)
			(end 0.67945 -0.3048)
			(stroke
				(width 0.1)
				(type default)
			)
			(layer "F.Fab")
		)
		(fp_line
			(start 0.120396 0.3048)
			(end 0.120396 0.2794)
			(stroke
				(width 0.1)
				(type default)
			)
			(layer "F.Fab")
		)
		(fp_line
			(start 0.120396 0.2794)
			(end -0.12065 0.2794)
			(stroke
				(width 0.1)
				(type default)
			)
			(layer "F.Fab")
		)
		(fp_line
			(start -0.12065 0.3048)
			(end -0.67945 0.3048)
			(stroke
				(width 0.1)
				(type default)
			)
			(layer "F.Fab")
		)
		(fp_line
			(start -0.12065 0.2794)
			(end -0.12065 0.3048)
			(stroke
				(width 0.1)
				(type default)
			)
			(layer "F.Fab")
		)
		(fp_line
			(start -0.12065 -0.2794)
			(end 0.12065 -0.2794)
			(stroke
				(width 0.1)
				(type default)
			)
			(layer "F.Fab")
		)
		(fp_line
			(start -0.12065 -0.305054)
			(end -0.12065 -0.2794)
			(stroke
				(width 0.1)
				(type default)
			)
			(layer "F.Fab")
		)
		(fp_line
			(start -0.67945 0.3048)
			(end -0.67945 -0.305054)
			(stroke
				(width 0.1)
				(type default)
			)
			(layer "F.Fab")
		)
		(fp_line
			(start -0.67945 -0.305054)
			(end -0.12065 -0.305054)
			(stroke
				(width 0.1)
				(type default)
			)
			(layer "F.Fab")
		)
		(pad "1" smd circle
			(at -0.40005 0 180)
			(size 0 0)
			(layers "F.Cu" "F.Mask" "F.Paste")
			(net "P12V_E1S_0")
		)
		(pad "2" smd circle
			(at 0.40005 0 180)
			(size 0 0)
			(layers "F.Cu" "F.Mask" "F.Paste")
			(net "VSENSE_P12V_INA230_8_INP")
		)
	)
	(footprint ""
		(layer "F.Cu")
		(at 399.171668 -395.066774 -90)
		(property "Reference" "R631"
			(at 0 0 270)
			(layer "F.SilkS")
			(hide yes)
			(effects
				(font
					(size 1.27 1.27)
				)
			)
		)
		(property "Value" ""
			(at 0 0 270)
			(layer "F.Fab")
			(effects
				(font
					(size 1.27 1.27)
				)
			)
		)
		(duplicate_pad_numbers_are_jumpers no)
		(fp_line
			(start -0.32512 0.175006)
			(end -0.32512 -0.175006)
			(stroke
				(width 0.1)
				(type default)
			)
			(layer "F.Fab")
		)
		(fp_line
			(start 0.32512 0.175006)
			(end -0.32512 0.175006)
			(stroke
				(width 0.1)
				(type default)
			)
			(layer "F.Fab")
		)
		(fp_line
			(start -0.32512 -0.175006)
			(end 0.32512 -0.175006)
			(stroke
				(width 0.1)
				(type default)
			)
			(layer "F.Fab")
		)
		(fp_line
			(start 0.32512 -0.175006)
			(end 0.32512 0.175006)
			(stroke
				(width 0.1)
				(type default)
			)
			(layer "F.Fab")
		)
		(pad "1" smd rect
			(at -0.2667 0 270)
			(size 0.3048 0.381)
			(layers "F.Cu" "F.Mask" "F.Paste")
			(net "CLK_100M_RETIMER_CPU0_P2_DN")
		)
		(pad "2" smd rect
			(at 0.2667 0 90)
			(size 0.3048 0.381)
			(layers "F.Cu" "F.Mask" "F.Paste")
			(net "GND")
		)
	)
	(footprint ""
		(layer "F.Cu")
		(at 64.614298 -24.798782 180)
		(property "Reference" "PC1320"
			(at 0 0 180)
			(layer "F.SilkS")
			(hide yes)
			(effects
				(font
					(size 1.27 1.27)
				)
			)
		)
		(property "Value" ""
			(at 0 0 180)
			(layer "F.Fab")
			(effects
				(font
					(size 1.27 1.27)
				)
			)
		)
		(duplicate_pad_numbers_are_jumpers no)
		(fp_line
			(start 1.2954 0.5842)
			(end -1.2954 0.5842)
			(stroke
				(width 0.1524)
				(type default)
			)
			(layer "F.SilkS")
		)
		(fp_line
			(start 1.2954 -0.5842)
			(end 1.2954 0.5842)
			(stroke
				(width 0.1524)
				(type default)
			)
			(layer "F.SilkS")
		)
		(fp_line
			(start -1.2954 0.5842)
			(end -1.2954 -0.5842)
			(stroke
				(width 0.1524)
				(type default)
			)
			(layer "F.SilkS")
		)
		(fp_line
			(start -1.2954 -0.5842)
			(end 1.2954 -0.5842)
			(stroke
				(width 0.1524)
				(type default)
			)
			(layer "F.SilkS")
		)
		(fp_line
			(start 1.1938 0.4064)
			(end 0.8636 0.4064)
			(stroke
				(width 0.1)
				(type default)
			)
			(layer "F.Fab")
		)
		(fp_line
			(start 1.1938 -0.4064)
			(end 1.1938 0.4064)
			(stroke
				(width 0.1)
				(type default)
			)
			(layer "F.Fab")
		)
		(fp_line
			(start 0.8636 0.4572)
			(end -0.8636 0.4572)
			(stroke
				(width 0.1)
				(type default)
			)
			(layer "F.Fab")
		)
		(fp_line
			(start 0.8636 0.4064)
			(end 0.8636 0.4572)
			(stroke
				(width 0.1)
				(type default)
			)
			(layer "F.Fab")
		)
		(fp_line
			(start 0.8636 -0.4064)
			(end 1.1938 -0.4064)
			(stroke
				(width 0.1)
				(type default)
			)
			(layer "F.Fab")
		)
		(fp_line
			(start 0.8636 -0.4572)
			(end 0.8636 -0.4064)
			(stroke
				(width 0.1)
				(type default)
			)
			(layer "F.Fab")
		)
		(fp_line
			(start -0.8636 0.4572)
			(end -0.8636 0.4064)
			(stroke
				(width 0.1)
				(type default)
			)
			(layer "F.Fab")
		)
		(fp_line
			(start -0.8636 0.4064)
			(end -1.1938 0.4064)
			(stroke
				(width 0.1)
				(type default)
			)
			(layer "F.Fab")
		)
		(fp_line
			(start -0.8636 -0.4064)
			(end -0.8636 -0.4572)
			(stroke
				(width 0.1)
				(type default)
			)
			(layer "F.Fab")
		)
		(fp_line
			(start -0.8636 -0.4572)
			(end 0.8636 -0.4572)
			(stroke
				(width 0.1)
				(type default)
			)
			(layer "F.Fab")
		)
		(fp_line
			(start -1.1938 0.4064)
			(end -1.1938 -0.4064)
			(stroke
				(width 0.1)
				(type default)
			)
			(layer "F.Fab")
		)
		(fp_line
			(start -1.1938 -0.4064)
			(end -0.8636 -0.4064)
			(stroke
				(width 0.1)
				(type default)
			)
			(layer "F.Fab")
		)
		(pad "1" smd rect
			(at -0.7366 0 90)
			(size 0.7112 0.8128)
			(layers "F.Cu" "F.Mask" "F.Paste")
			(net "P12V_OCP_AVIN_PD_2")
		)
		(pad "2" smd rect
			(at 0.7366 0 90)
			(size 0.7112 0.8128)
			(layers "F.Cu" "F.Mask" "F.Paste")
			(net "GND")
		)
	)
)
